FILE_TYPE = MACRO_DRAWING;
SET COLOR_WIRE YELLOW;
SET COLOR_PROP MONO;
SET COLOR_DOT WHITE;
SET COLOR_ARC YELLOW;
SET COLOR_BODY GREEN;
SET COLOR_NOTE MONO;
SET PROP_DISPLAY VALUE;
SET PAGE_NUMBER P13;
FORCEADD INTEL_CORP_BPAGE..1
(0 0);
FORCEPROP 1 LAST CDS_CON_LAST_MODIFIED Fri Jun 16 17:48:01 2017
J 0
(-1425 325);
PAINT ORANGE (-1425 325);
DISPLAY INVISIBLE (-1425 325);
FORCEPROP 1 LAST CUSTOM_TXT_CDS <CURRENT_DESIGN_SHEET> OF <TOTAL_DESIGN_SHEETS>
J 0
(-500 25);
PAINT ORANGE (-500 25);
FORCEPROP 1 LAST CUSTOM_TXT_CDS <CON_LAST_MODIFIED>
J 0
(-4000 100);
PAINT ORANGE (-4000 100);
FORCEPROP 2 LAST CUSTOM_TXT_CDS <XR_PAGE_TITLE>
J 0
(-7890 5250);
DISPLAY 0.638298 (-7890 5250);
PAINT PINK (-7890 5250);
DISPLAY INVISIBLE (-7890 5250);
FORCEPROP 1 LAST SCH_TITLE XDP BLOCK DIAGRAM
J 0
(-7950 50);
DISPLAY 1.212766 (-7950 50);
PAINT ORANGE (-7950 50);
FORCEPROP 1 LAST COMMENT_BODY TRUE
J 0
(12 12);
DISPLAY 0.468085 (12 12);
PAINT GREEN (12 12);
DISPLAY INVISIBLE (12 12);
FORCEPROP 2 LAST CDS_LIB mstr_symbols
J 0
(0 0);
PAINT ORANGE (0 0);
DISPLAY INVISIBLE (0 0);
FORCEPROP 2 LAST PAGE_BORDER TRUE
J 0
(-7890 5250);
DISPLAY 0.638298 (-7890 5250);
PAINT PINK (-7890 5250);
DISPLAY INVISIBLE (-7890 5250);
FORCEPROP 2 LAST CDS_XR_PAGE_TITLE CR-13 : @BASEBOARD_FAB2_LIB.BASEBOARD_FAB2(SCH_1):PAGE13
J 0
(-7890 5250);
DISPLAY 0.638298 (-7890 5250);
PAINT PINK (-7890 5250);
DISPLAY INVISIBLE (-7890 5250);
FORCENOTE
$CDS_IMAGE|BMC_Remote_Proposal_20170111C.jpg|6757|4750
(-3975 2625) 0;
DISPLAY LEFT (-3975 2625);
QUIT
